# T6G (Grand Teton) — schematic parts with pin connectivity, parts 2600–2600 of 8303; source: Cadence DE-HDL packaged netlist (pstxprt.dat, pstxnet.dat, pstchip.dat)

J18  SCONN288_DDR506112002KQ  IO  pkg DDR288S_1-1VXC  page 94
  1  VIN_BULK0  POWER  = P12V_MEM_CPU0
  2  RFU0  TRI  = NC
  3  VIN_MGMT  POWER  = P3V3_AUX
  4  HSCL  IN  = I3C_SPD_DDRI_CPU0_SCL
  5  HSDA  BI  = I3C_SPD_DDRI_CPU0_SDA
  6  VSS0  POWER  = GND
  7  DQ0_A  BI  = M_I_CPU0_SA_DQ<0>
  8  VSS1  POWER  = GND
  9  DQ1_A  BI  = M_I_CPU0_SA_DQ<1>
  10  VSS2  POWER  = GND
  11  DQS0_A_T  BI  = M_I_CPU0_SA_DQS_DP<0>
  12  DQS0_A_C  BI  = M_I_CPU0_SA_DQS_DN<0>
  13  VSS3  POWER  = GND
  14  DQ4_A  BI  = M_I_CPU0_SA_DQ<4>
  15  VSS4  POWER  = GND
  16  DQ5_A  BI  = M_I_CPU0_SA_DQ<5>
  17  VSS5  POWER  = GND
  18  DQ8_A  BI  = M_I_CPU0_SA_DQ<8>
  19  VSS6  POWER  = GND
  20  DQ9_A  BI  = M_I_CPU0_SA_DQ<9>
  21  VSS7  POWER  = GND
  22  DQS1_A_T  BI  = M_I_CPU0_SA_DQS_DP<1>
  23  DQS1_A_C  BI  = M_I_CPU0_SA_DQS_DN<1>
  24  VSS8  POWER  = GND
  25  DQ12_A  BI  = M_I_CPU0_SA_DQ<12>
  26  VSS9  POWER  = GND
  27  DQ13_A  BI  = M_I_CPU0_SA_DQ<13>
  28  VSS10  POWER  = GND
  29  DQ16_A  BI  = M_I_CPU0_SA_DQ<16>
  30  VSS11  POWER  = GND
  31  DQ17_A  BI  = M_I_CPU0_SA_DQ<17>
  32  VSS12  POWER  = GND
  33  DQS2_A_T  BI  = M_I_CPU0_SA_DQS_DP<2>
  34  DQS2_A_C  BI  = M_I_CPU0_SA_DQS_DN<2>
  35  VSS13  POWER  = GND
  36  DQ20_A  BI  = M_I_CPU0_SA_DQ<20>
  37  VSS14  POWER  = GND
  38  DQ21_A  BI  = M_I_CPU0_SA_DQ<21>
  39  VSS15  POWER  = GND
  40  DQ24_A  BI  = M_I_CPU0_SA_DQ<24>
  41  VSS16  POWER  = GND
  42  DQ25_A  BI  = M_I_CPU0_SA_DQ<25>
  43  VSS17  POWER  = GND
  44  DQS3_A_T  BI  = M_I_CPU0_SA_DQS_DP<3>
  45  DQS3_A_C  BI  = M_I_CPU0_SA_DQS_DN<3>
  46  VSS18  POWER  = GND
  47  DQ28_A  BI  = M_I_CPU0_SA_DQ<28>
  48  VSS19  POWER  = GND
  49  DQ29_A  BI  = M_I_CPU0_SA_DQ<29>
  50  VSS20  POWER  = GND
  51  CB0_A  BI  = M_I_CPU0_SA_CB<0>
  52  VSS21  POWER  = GND
  53  CB1_A  BI  = M_I_CPU0_SA_CB<1>
  54  VSS22  POWER  = GND
  55  DQS4_A_T  BI  = M_I_CPU0_SA_DQS_DP<4>
  56  DQS4_A_C  BI  = M_I_CPU0_SA_DQS_DN<4>
  57  VSS23  POWER  = GND
  58  CB4_A  BI  = M_I_CPU0_SA_CB<4>
  59  VSS24  POWER  = GND
  60  CB5_A  BI  = M_I_CPU0_SA_CB<5>
  61  VSS25  POWER  = GND
  62  ALERT_N  OUT  = M_I_CPU0_ALERT_N
  63  VSS26  POWER  = GND
  64  CS0_A_N  IN  = M_I_CPU0_SA_CS_N<0>
  65  VSS27  POWER  = GND
  66  CA0_A  IN  = M_I_CPU0_SA_CA<0>
  67  VSS28  POWER  = GND
  68  CA2_A  IN  = M_I_CPU0_SA_CA<2>
  69  VSS29  POWER  = GND
  70  CA4_A  IN  = M_I_CPU0_SA_CA<4>
  71  VSS30  POWER  = GND
  72  CA6_A  IN  = M_I_CPU0_SA_CA<6>
  73  VSS31  POWER  = GND
  74  PAR_A  IN  = M_I_CPU0_SA_PAR
  75  VSS32  POWER  = GND
  76  CA0_B  IN  = M_I_CPU0_SB_CA<0>
  77  VSS33  POWER  = GND
  78  CA2_B  IN  = M_I_CPU0_SB_CA<2>
  79  VSS34  POWER  = GND
  80  CA4_B  IN  = M_I_CPU0_SB_CA<4>
  81  VSS35  POWER  = GND
  82  CA6_B  IN  = M_I_CPU0_SB_CA<6>
  83  VSS36  POWER  = GND
  84  CS0_B_N  IN  = M_I_CPU0_SB_CS_N<0>
  85  VSS37  POWER  = GND
  86  \lbd||rsp_a_n\  OUT  = M_I_CPU0_SA_RSP<0>
  87  \lbs||rsp_b_n\  OUT  = M_I_CPU0_SB_RSP<0>
  88  VSS38  POWER  = GND
  89  CB4_B  BI  = M_I_CPU0_SB_CB<4>
  90  VSS39  POWER  = GND
  91  CB5_B  BI  = M_I_CPU0_SB_CB<5>
  92  VSS40  POWER  = GND
  93  \dqs9_b_t||tdqs9_b_t||dbi4_b_n\  BI  = M_I_CPU0_SB_DQS_DP<9>
  94  \dqs9_b_c||tdqs9_b_c\  BI  = M_I_CPU0_SB_DQS_DN<9>
  95  VSS41  POWER  = GND
  96  CB0_B  BI  = M_I_CPU0_SB_CB<0>
  97  VSS42  POWER  = GND
  98  CB1_B  BI  = M_I_CPU0_SB_CB<1>
  99  VSS43  POWER  = GND
  100  DQ0_B  BI  = M_I_CPU0_SB_DQ<0>
  101  VSS44  POWER  = GND
  102  DQ1_B  BI  = M_I_CPU0_SB_DQ<1>
  103  VSS45  POWER  = GND
  104  DQS0_B_T  BI  = M_I_CPU0_SB_DQS_DP<0>
  105  DQS0_B_C  BI  = M_I_CPU0_SB_DQS_DN<0>
  106  VSS46  POWER  = GND
  107  DQ4_B  BI  = M_I_CPU0_SB_DQ<4>
  108  VSS47  POWER  = GND
  109  DQ5_B  BI  = M_I_CPU0_SB_DQ<5>
  110  VSS48  POWER  = GND
  111  DQ8_B  BI  = M_I_CPU0_SB_DQ<8>
  112  VSS49  POWER  = GND
  113  DQ9_B  BI  = M_I_CPU0_SB_DQ<9>
  114  VSS50  POWER  = GND
  115  DQS1_B_T  BI  = M_I_CPU0_SB_DQS_DP<1>
  116  DQS1_B_C  BI  = M_I_CPU0_SB_DQS_DN<1>
  117  VSS51  POWER  = GND
  118  DQ12_B  BI  = M_I_CPU0_SB_DQ<12>
  119  VSS52  POWER  = GND
  120  DQ13_B  BI  = M_I_CPU0_SB_DQ<13>
  121  VSS53  POWER  = GND
  122  DQ16_B  BI  = M_I_CPU0_SB_DQ<16>
  123  VSS54  POWER  = GND
  124  DQ17_B  BI  = M_I_CPU0_SB_DQ<17>
  125  VSS55  POWER  = GND
  126  DQS2_B_T  BI  = M_I_CPU0_SB_DQS_DP<2>
  127  DQS2_B_C  BI  = M_I_CPU0_SB_DQS_DN<2>
  128  VSS56  POWER  = GND
  129  DQ20_B  BI  = M_I_CPU0_SB_DQ<20>
  130  VSS57  POWER  = GND
  131  DQ21_B  BI  = M_I_CPU0_SB_DQ<21>
  132  VSS58  POWER  = GND
  133  DQ24_B  BI  = M_I_CPU0_SB_DQ<24>
  134  VSS59  POWER  = GND
  135  DQ25_B  BI  = M_I_CPU0_SB_DQ<25>
  136  VSS60  POWER  = GND
  137  DQS3_B_T  BI  = M_I_CPU0_SB_DQS_DP<3>
  138  DQS3_B_C  BI  = M_I_CPU0_SB_DQS_DN<3>
  139  VSS61  POWER  = GND
  140  DQ28_B  BI  = M_I_CPU0_SB_DQ<28>
  141  VSS62  POWER  = GND
  142  DQ29_B  BI  = M_I_CPU0_SB_DQ<29>
  143  VSS63  POWER  = GND
  144  RFU1  TRI  = NC
  145  VIN_BULK1  POWER  = P12V_MEM_CPU0
  146  VIN_BULK2  POWER  = P12V_MEM_CPU0
  147  \pwr_good||fail_n\  BI  = PWRGD_CHI_CPU0_DIMM
  148  HAS  IN  = PD_CHI_CPU0_DIMM_SAA
  149  RFU2  TRI  = NC
  150  RFU3  TRI  = NC
  151  VSS64  POWER  = GND
  152  DQ2_A  BI  = M_I_CPU0_SA_DQ<2>
  153  VSS65  POWER  = GND
  154  DQ3_A  BI  = M_I_CPU0_SA_DQ<3>
  155  VSS66  POWER  = GND
  156  \dqs5_a_c||tdqs5_a_c||dqs5_a_t||tdqs5_a_t\  BI  = M_I_CPU0_SA_DQS_DN<5>
  157  \dqs5_a_t||tdqs5_a_t\  BI  = M_I_CPU0_SA_DQS_DP<5>
  158  VSS67  POWER  = GND
  159  DQ6_A  BI  = M_I_CPU0_SA_DQ<6>
  160  VSS68  POWER  = GND
  161  DQ7_A  BI  = M_I_CPU0_SA_DQ<7>
  162  VSS69  POWER  = GND
  163  DQ10_A  BI  = M_I_CPU0_SA_DQ<10>
  164  VSS70  POWER  = GND
  165  DQ11_A  BI  = M_I_CPU0_SA_DQ<11>
  166  VSS71  POWER  = GND
  167  \dqs6_a_c||tdqs6_a_c||dqs6_a_t||tdqs6_a_t\  BI  = M_I_CPU0_SA_DQS_DN<6>
  168  \dqs6_a_t||tdqs6_a_t\  BI  = M_I_CPU0_SA_DQS_DP<6>
  169  VSS72  POWER  = GND
  170  DQ14_A  BI  = M_I_CPU0_SA_DQ<14>
  171  VSS73  POWER  = GND
  172  DQ15_A  BI  = M_I_CPU0_SA_DQ<15>
  173  VSS74  POWER  = GND
  174  DQ18_A  BI  = M_I_CPU0_SA_DQ<18>
  175  VSS75  POWER  = GND
  176  DQ19_A  BI  = M_I_CPU0_SA_DQ<19>
  177  VSS76  POWER  = GND
  178  \dqs7_a_c||tdqs7_a_c\  BI  = M_I_CPU0_SA_DQS_DN<7>
  179  \dqs7_a_t||tdqs7_a_t\  BI  = M_I_CPU0_SA_DQS_DP<7>
  180  VSS77  POWER  = GND
  181  DQ22_A  BI  = M_I_CPU0_SA_DQ<22>
  182  VSS78  POWER  = GND
  183  DQ23_A  BI  = M_I_CPU0_SA_DQ<23>
  184  VSS79  POWER  = GND
  185  DQ26_A  BI  = M_I_CPU0_SA_DQ<26>
  186  VSS80  POWER  = GND
  187  DQ27_A  BI  = M_I_CPU0_SA_DQ<27>
  188  VSS81  POWER  = GND
  189  \dqs8_a_c||tdqs8_a_c\  BI  = M_I_CPU0_SA_DQS_DN<8>
  190  \dqs8_a_t||tdqs8_a_t\  BI  = M_I_CPU0_SA_DQS_DP<8>
  191  VSS82  POWER  = GND
  192  DQ30_A  BI  = M_I_CPU0_SA_DQ<30>
  193  VSS83  POWER  = GND
  194  DQ31_A  BI  = M_I_CPU0_SA_DQ<31>
  195  VSS84  POWER  = GND
  196  CB2_A  BI  = M_I_CPU0_SA_CB<2>
  197  VSS85  POWER  = GND
  198  CB3_A  BI  = M_I_CPU0_SA_CB<3>
  199  VSS86  POWER  = GND
  200  \dqs9_a_c||tdqs9_a_c\  BI  = M_I_CPU0_SA_DQS_DN<9>
  201  \dqs9_a_t||tdqs9_a_t\  BI  = M_I_CPU0_SA_DQS_DP<9>
  202  VSS87  POWER  = GND
  203  CB6_A  BI  = M_I_CPU0_SA_CB<6>
  204  VSS88  POWER  = GND
  205  CB7_A  BI  = M_I_CPU0_SA_CB<7>
  206  VSS89  POWER  = GND
  207  RESET_N  IN  = M_I_CPU0_RESET_N
  208  VSS90  POWER  = GND
  209  CS1_A_N  IN  = M_I_CPU0_SA_CS_N<1>
  210  VSS91  POWER  = GND
  211  CA1_A  IN  = M_I_CPU0_SA_CA<1>
  212  VSS92  POWER  = GND
  213  CA3_A  IN  = M_I_CPU0_SA_CA<3>
  214  VSS93  POWER  = GND
  215  CA5_A  IN  = M_I_CPU0_SA_CA<5>
  216  VSS94  POWER  = GND
  217  CK_T  IN  = M_I_CPU0_CLK_DP<0>
  218  CK_C  IN  = M_I_CPU0_CLK_DN<0>
  219  VSS95  POWER  = GND
  220  RFU4  TRI  = NC
  221  CA1_B  IN  = M_I_CPU0_SB_CA<1>
  222  VSS96  POWER  = GND
  223  CA3_B  IN  = M_I_CPU0_SB_CA<3>
  224  VSS97  POWER  = GND
  225  CA5_B  IN  = M_I_CPU0_SB_CA<5>
  226  VSS98  POWER  = GND
  227  PAR_B  IN  = M_I_CPU0_SB_PAR
  228  VSS99  POWER  = GND
  229  CS1_B_N  IN  = M_I_CPU0_SB_CS_N<1>
  230  VSS100  POWER  = GND
  231  RFU5  TRI  = NC
  232  RFU6  TRI  = NC
  233  VSS101  POWER  = GND
  234  CB6_B  BI  = M_I_CPU0_SB_CB<6>
  235  VSS102  POWER  = GND
  236  CB7_B  BI  = M_I_CPU0_SB_CB<7>
  237  VSS103  POWER  = GND
  238  DQS4_B_C  BI  = M_I_CPU0_SB_DQS_DN<4>
  239  DQS4_B_T  BI  = M_I_CPU0_SB_DQS_DP<4>
  240  VSS104  POWER  = GND
  241  CB2_B  BI  = M_I_CPU0_SB_CB<2>
  242  VSS105  POWER  = GND
  243  CB3_B  BI  = M_I_CPU0_SB_CB<3>
  244  VSS106  POWER  = GND
  245  DQ2_B  BI  = M_I_CPU0_SB_DQ<2>
  246  VSS107  POWER  = GND
  247  DQ3_B  BI  = M_I_CPU0_SB_DQ<3>
  248  VSS108  POWER  = GND
  249  \dqs5_b_c||tdqs5_b_c\  BI  = M_I_CPU0_SB_DQS_DN<5>
  250  \dqs5_b_t||tdqs5_b_t\  BI  = M_I_CPU0_SB_DQS_DP<5>
  251  VSS109  POWER  = GND
  252  DQ6_B  BI  = M_I_CPU0_SB_DQ<6>
  253  VSS110  POWER  = GND
  254  DQ7_B  BI  = M_I_CPU0_SB_DQ<7>
  255  VSS111  POWER  = GND
  256  DQ10_B  BI  = M_I_CPU0_SB_DQ<10>
  257  VSS112  POWER  = GND
  258  DQ11_B  BI  = M_I_CPU0_SB_DQ<11>
  259  VSS113  POWER  = GND
  260  \dqs6_b_c||tdqs6_b_c\  BI  = M_I_CPU0_SB_DQS_DN<6>
  261  \dqs6_b_t||tdqs6_b_t\  BI  = M_I_CPU0_SB_DQS_DP<6>
  262  VSS114  POWER  = GND
  263  DQ14_B  BI  = M_I_CPU0_SB_DQ<14>
  264  VSS115  POWER  = GND
  265  DQ15_B  BI  = M_I_CPU0_SB_DQ<15>
  266  VSS116  POWER  = GND
  267  DQ18_B  BI  = M_I_CPU0_SB_DQ<18>
  268  VSS117  POWER  = GND
  269  DQ19_B  BI  = M_I_CPU0_SB_DQ<19>
  270  VSS118  POWER  = GND
  271  \dqs7_b_c||tdqs7_b_c\  BI  = M_I_CPU0_SB_DQS_DN<7>
  272  \dqs7_b_t||tdqs7_b_t\  BI  = M_I_CPU0_SB_DQS_DP<7>
  273  VSS119  POWER  = GND
  274  DQ22_B  BI  = M_I_CPU0_SB_DQ<22>
  275  VSS120  POWER  = GND
  276  DQ23_B  BI  = M_I_CPU0_SB_DQ<23>
  277  VSS121  POWER  = GND
  278  DQ26_B  BI  = M_I_CPU0_SB_DQ<26>
  279  VSS122  POWER  = GND
  280  DQ27_B  BI  = M_I_CPU0_SB_DQ<27>
  281  VSS123  POWER  = GND
  282  \dqs8_b_c||tdqs8_b_c\  BI  = M_I_CPU0_SB_DQS_DN<8>
  283  \dqs8_b_t||tdqs8_b_t\  BI  = M_I_CPU0_SB_DQS_DP<8>
  284  VSS124  POWER  = GND
  285  DQ30_B  BI  = M_I_CPU0_SB_DQ<30>
  286  VSS125  POWER  = GND
  287  DQ31_B  BI  = M_I_CPU0_SB_DQ<31>
  288  VSS126  POWER  = GND
  G1  G1  POWER  = GND
  G2  G2  POWER  = GND
  G3  G3  POWER  = GND
